# Stackup_F0T_Fan_BP_6L_1p6mm_IT-170GT_RTF_Rev0p1_20211021.xls — Vendor Stackup (pcb-stackup)
| STACKUP |  |  |  | Target Z (ohms) - MicroStrip |  |  |  |  |  |  |  | 50 |  |  | Breakout |
|  |  |  |  | Target Z (ohms) - StripLine |  |  |  |  |  |  |  | 50 |  |  |  |
|  |  |  |  | Z tolerance |  |  |  |  |  |  |  | 0.1 |  |  |  |
|  |  |  |  | Z Type |  |  |  |  |  |  |  | Single |  |  | Single |
| Layer# | Material | Description |  | Copper Weight (oz) | Thickness (mil) | Tolerance (mil) | Glass Fabric | Er | Vendor Thickness (mil) | Vendor Glass Fabric | Vendor Er | Width | Vendor Width | Vendor Impedance | Width |
|  |  |  | Soldermask |  | 0.6 |  |  | 3.8 |  |  |  |  |  |  |  |
| 1 |  |  | TOP | 0.5+plating | 1.95 |  |  |  |  |  |  | 10.5 |  |  | 4 |
|  | IT-170GT |  | PP |  | 6 | ±0.984 | Vendor Define | 3.89 |  |  |  |  |  |  |  |
| 2 |  |  | GND | 2 (RTF) | 2.6 |  |  |  |  |  |  |  |  |  |  |
|  | IT-170GT |  | CORE |  | 6 | ±0.984 | 1080x2 | 3.89 |  |  |  |  |  |  |  |
| 3 |  |  | IN1 | 1 (RTF) | 1.3 |  |  |  |  |  |  | 8.5 |  |  | 4 |
|  | IT-170GT |  | PP |  | 26.1 | ±2.52 | Vendor Define | 4.08 |  |  |  |  |  |  |  |
| 4 |  |  | IN2 | 1 (RTF) | 1.3 |  |  |  |  |  |  | 8.5 |  |  | 4 |
|  | IT-170GT |  | CORE |  | 6 | ±0.984 | 1080x2 | 3.89 |  |  |  |  |  |  |  |
| 5 |  |  | GND1 | 2 (RTF) | 2.6 |  |  |  |  |  |  |  |  |  |  |
|  | IT-170GT |  | PP |  | 6 | ±0.984 | Vendor Define | 3.89 |  |  |  |  |  |  |  |
| 6 |  |  | BOTTOM | 0.5+plating | 1.95 |  |  |  |  |  |  | 10.5 |  |  | 4 |
|  |  |  | Soldermask |  | 0.6 |  |  | 3.8 |  |  |  |  |  |  |  |
|  |  |  |  | Total | 63 | ±10% |  |  | 0 |  |  |  |  |  |  |
